(kicad_pcb
	(version 20260206)
	(generator "pcbnew")
	(generator_version "10.0")
	(general
		(thickness 1.6)
		(legacy_teardrops no)
	)
	(paper "A4")
	(title_block
		(title "01162023_DA0F0TEBIF0_F0T_Expander_BD_F_brd_V02_OCP.brd")
		(comment 1 "Grand Teton / footprints 8472-8477 of 9728")
	)
	(layers
		(0 "F.Cu" signal "TOP")
		(4 "In1.Cu" signal "GND")
		(6 "In2.Cu" signal "VCC")
		(8 "In3.Cu" signal "VCC1")
		(10 "In4.Cu" signal "GND1")
		(12 "In5.Cu" signal "IN1")
		(14 "In6.Cu" signal "GND2")
		(16 "In7.Cu" signal "IN2")
		(18 "In8.Cu" signal "GND3")
		(20 "In9.Cu" signal "IN3")
		(22 "In10.Cu" signal "GND4")
		(24 "In11.Cu" signal "IN4")
		(26 "In12.Cu" signal "GND5")
		(28 "In13.Cu" signal "IN5")
		(30 "In14.Cu" signal "GND6")
		(32 "In15.Cu" signal "IN6")
		(34 "In16.Cu" signal "GND7")
		(2 "B.Cu" signal "BOTTOM")
		(9 "F.Adhes" user "F.Adhesive")
		(11 "B.Adhes" user "B.Adhesive")
		(13 "F.Paste" user "Package Geometry/Pastemask Top")
		(15 "B.Paste" user "Package Geometry/Pastemask Bottom")
		(5 "F.SilkS" user "Ref Des/Silkscreen Top")
		(7 "B.SilkS" user "Ref Des/Silkscreen Bottom")
		(1 "F.Mask" user "Board Geometry/Soldermask Top")
		(3 "B.Mask" user "Board Geometry/Soldermask Bottom")
		(17 "Dwgs.User" user "User.Drawings")
		(19 "Cmts.User" user "User.Comments")
		(21 "Eco1.User" user "User.Eco1")
		(23 "Eco2.User" user "User.Eco2")
		(25 "Edge.Cuts" user "Board Geometry/Outline")
		(27 "Margin" user)
		(31 "F.CrtYd" user "Package Geometry/Place Bound Top")
		(29 "B.CrtYd" user "Package Geometry/Place Bound Bottom")
		(35 "F.Fab" user "Ref Des/Assembly Top")
		(33 "B.Fab" user "Ref Des/Assembly Bottom")
	)
	(footprint ""
		(layer "B.Cu")
		(at 389.443976 -247.161304 90)
		(property "Reference" "R937"
			(at 0 0 90)
			(layer "B.SilkS")
			(hide yes)
			(effects
				(font
					(size 1.27 1.27)
				)
				(justify mirror)
			)
		)
		(property "Value" ""
			(at 0 0 90)
			(layer "B.Fab")
			(effects
				(font
					(size 1.27 1.27)
				)
				(justify mirror)
			)
		)
		(duplicate_pad_numbers_are_jumpers no)
		(fp_line
			(start 0.7874 -0.4064)
			(end -0.7874 -0.4064)
			(stroke
				(width 0.1524)
				(type default)
			)
			(layer "B.SilkS")
		)
		(fp_line
			(start -0.7874 -0.4064)
			(end -0.7874 0.4064)
			(stroke
				(width 0.1524)
				(type default)
			)
			(layer "B.SilkS")
		)
		(fp_line
			(start 0.7874 0.4064)
			(end 0.7874 -0.4064)
			(stroke
				(width 0.1524)
				(type default)
			)
			(layer "B.SilkS")
		)
		(fp_line
			(start -0.7874 0.4064)
			(end 0.7874 0.4064)
			(stroke
				(width 0.1524)
				(type default)
			)
			(layer "B.SilkS")
		)
		(fp_line
			(start 0.67945 -0.305054)
			(end 0.12065 -0.305054)
			(stroke
				(width 0.1)
				(type default)
			)
			(layer "B.Fab")
		)
		(fp_line
			(start 0.12065 -0.305054)
			(end 0.12065 -0.2794)
			(stroke
				(width 0.1)
				(type default)
			)
			(layer "B.Fab")
		)
		(fp_line
			(start -0.12065 -0.3048)
			(end -0.67945 -0.3048)
			(stroke
				(width 0.1)
				(type default)
			)
			(layer "B.Fab")
		)
		(fp_line
			(start -0.67945 -0.3048)
			(end -0.67945 0.3048)
			(stroke
				(width 0.1)
				(type default)
			)
			(layer "B.Fab")
		)
		(fp_line
			(start 0.12065 -0.2794)
			(end -0.12065 -0.2794)
			(stroke
				(width 0.1)
				(type default)
			)
			(layer "B.Fab")
		)
		(fp_line
			(start -0.12065 -0.2794)
			(end -0.12065 -0.3048)
			(stroke
				(width 0.1)
				(type default)
			)
			(layer "B.Fab")
		)
		(fp_line
			(start 0.12065 0.2794)
			(end 0.12065 0.3048)
			(stroke
				(width 0.1)
				(type default)
			)
			(layer "B.Fab")
		)
		(fp_line
			(start -0.120396 0.2794)
			(end 0.12065 0.2794)
			(stroke
				(width 0.1)
				(type default)
			)
			(layer "B.Fab")
		)
		(fp_line
			(start 0.67945 0.3048)
			(end 0.67945 -0.305054)
			(stroke
				(width 0.1)
				(type default)
			)
			(layer "B.Fab")
		)
		(fp_line
			(start 0.12065 0.3048)
			(end 0.67945 0.3048)
			(stroke
				(width 0.1)
				(type default)
			)
			(layer "B.Fab")
		)
		(fp_line
			(start -0.120396 0.3048)
			(end -0.120396 0.2794)
			(stroke
				(width 0.1)
				(type default)
			)
			(layer "B.Fab")
		)
		(fp_line
			(start -0.67945 0.3048)
			(end -0.120396 0.3048)
			(stroke
				(width 0.1)
				(type default)
			)
			(layer "B.Fab")
		)
		(pad "1" smd circle
			(at 0.40005 0 270)
			(size 0 0)
			(layers "B.Cu" "B.Mask" "B.Paste")
			(net "UART_PEX2_SDB_BUF_RX")
		)
		(pad "2" smd circle
			(at -0.40005 0 270)
			(size 0 0)
			(layers "B.Cu" "B.Mask" "B.Paste")
			(net "P1V8_PEX")
		)
	)
	(footprint ""
		(layer "B.Cu")
		(at 49.5554 -154.0256)
		(property "Reference" "R21"
			(at 0 0 0)
			(layer "B.SilkS")
			(hide yes)
			(effects
				(font
					(size 1.27 1.27)
				)
				(justify mirror)
			)
		)
		(property "Value" ""
			(at 0 0 0)
			(layer "B.Fab")
			(effects
				(font
					(size 1.27 1.27)
				)
				(justify mirror)
			)
		)
		(duplicate_pad_numbers_are_jumpers no)
		(fp_line
			(start -0.7874 -0.4064)
			(end -0.7874 0.4064)
			(stroke
				(width 0.1524)
				(type default)
			)
			(layer "B.SilkS")
		)
		(fp_line
			(start -0.7874 0.4064)
			(end 0.7874 0.4064)
			(stroke
				(width 0.1524)
				(type default)
			)
			(layer "B.SilkS")
		)
		(fp_line
			(start 0.7874 -0.4064)
			(end -0.7874 -0.4064)
			(stroke
				(width 0.1524)
				(type default)
			)
			(layer "B.SilkS")
		)
		(fp_line
			(start 0.7874 0.4064)
			(end 0.7874 -0.4064)
			(stroke
				(width 0.1524)
				(type default)
			)
			(layer "B.SilkS")
		)
		(fp_line
			(start -0.67945 -0.3048)
			(end -0.67945 0.3048)
			(stroke
				(width 0.1)
				(type default)
			)
			(layer "B.Fab")
		)
		(fp_line
			(start -0.67945 0.3048)
			(end -0.120396 0.3048)
			(stroke
				(width 0.1)
				(type default)
			)
			(layer "B.Fab")
		)
		(fp_line
			(start -0.12065 -0.3048)
			(end -0.67945 -0.3048)
			(stroke
				(width 0.1)
				(type default)
			)
			(layer "B.Fab")
		)
		(fp_line
			(start -0.12065 -0.2794)
			(end -0.12065 -0.3048)
			(stroke
				(width 0.1)
				(type default)
			)
			(layer "B.Fab")
		)
		(fp_line
			(start -0.120396 0.2794)
			(end 0.12065 0.2794)
			(stroke
				(width 0.1)
				(type default)
			)
			(layer "B.Fab")
		)
		(fp_line
			(start -0.120396 0.3048)
			(end -0.120396 0.2794)
			(stroke
				(width 0.1)
				(type default)
			)
			(layer "B.Fab")
		)
		(fp_line
			(start 0.12065 -0.305054)
			(end 0.12065 -0.2794)
			(stroke
				(width 0.1)
				(type default)
			)
			(layer "B.Fab")
		)
		(fp_line
			(start 0.12065 -0.2794)
			(end -0.12065 -0.2794)
			(stroke
				(width 0.1)
				(type default)
			)
			(layer "B.Fab")
		)
		(fp_line
			(start 0.12065 0.2794)
			(end 0.12065 0.3048)
			(stroke
				(width 0.1)
				(type default)
			)
			(layer "B.Fab")
		)
		(fp_line
			(start 0.12065 0.3048)
			(end 0.67945 0.3048)
			(stroke
				(width 0.1)
				(type default)
			)
			(layer "B.Fab")
		)
		(fp_line
			(start 0.67945 -0.305054)
			(end 0.12065 -0.305054)
			(stroke
				(width 0.1)
				(type default)
			)
			(layer "B.Fab")
		)
		(fp_line
			(start 0.67945 0.3048)
			(end 0.67945 -0.305054)
			(stroke
				(width 0.1)
				(type default)
			)
			(layer "B.Fab")
		)
		(pad "1" smd circle
			(at 0.40005 0 180)
			(size 0 0)
			(layers "B.Cu" "B.Mask" "B.Paste")
			(net "NCSI_NIC0_TX_EN")
		)
		(pad "2" smd circle
			(at -0.40005 0 180)
			(size 0 0)
			(layers "B.Cu" "B.Mask" "B.Paste")
			(net "GND")
		)
	)
	(footprint ""
		(layer "B.Cu")
		(at 273.799808 -288.774886 90)
		(property "Reference" "R6159"
			(at 0 0 90)
			(layer "B.SilkS")
			(hide yes)
			(effects
				(font
					(size 1.27 1.27)
				)
				(justify mirror)
			)
		)
		(property "Value" ""
			(at 0 0 90)
			(layer "B.Fab")
			(effects
				(font
					(size 1.27 1.27)
				)
				(justify mirror)
			)
		)
		(duplicate_pad_numbers_are_jumpers no)
		(fp_line
			(start 0.7874 -0.4064)
			(end -0.7874 -0.4064)
			(stroke
				(width 0.1524)
				(type default)
			)
			(layer "B.SilkS")
		)
		(fp_line
			(start -0.7874 -0.4064)
			(end -0.7874 0.4064)
			(stroke
				(width 0.1524)
				(type default)
			)
			(layer "B.SilkS")
		)
		(fp_line
			(start 0.7874 0.4064)
			(end 0.7874 -0.4064)
			(stroke
				(width 0.1524)
				(type default)
			)
			(layer "B.SilkS")
		)
		(fp_line
			(start -0.7874 0.4064)
			(end 0.7874 0.4064)
			(stroke
				(width 0.1524)
				(type default)
			)
			(layer "B.SilkS")
		)
		(fp_line
			(start 0.67945 -0.305054)
			(end 0.12065 -0.305054)
			(stroke
				(width 0.1)
				(type default)
			)
			(layer "B.Fab")
		)
		(fp_line
			(start 0.12065 -0.305054)
			(end 0.12065 -0.2794)
			(stroke
				(width 0.1)
				(type default)
			)
			(layer "B.Fab")
		)
		(fp_line
			(start -0.12065 -0.3048)
			(end -0.67945 -0.3048)
			(stroke
				(width 0.1)
				(type default)
			)
			(layer "B.Fab")
		)
		(fp_line
			(start -0.67945 -0.3048)
			(end -0.67945 0.3048)
			(stroke
				(width 0.1)
				(type default)
			)
			(layer "B.Fab")
		)
		(fp_line
			(start 0.12065 -0.2794)
			(end -0.12065 -0.2794)
			(stroke
				(width 0.1)
				(type default)
			)
			(layer "B.Fab")
		)
		(fp_line
			(start -0.12065 -0.2794)
			(end -0.12065 -0.3048)
			(stroke
				(width 0.1)
				(type default)
			)
			(layer "B.Fab")
		)
		(fp_line
			(start 0.12065 0.2794)
			(end 0.12065 0.3048)
			(stroke
				(width 0.1)
				(type default)
			)
			(layer "B.Fab")
		)
		(fp_line
			(start -0.120396 0.2794)
			(end 0.12065 0.2794)
			(stroke
				(width 0.1)
				(type default)
			)
			(layer "B.Fab")
		)
		(fp_line
			(start 0.67945 0.3048)
			(end 0.67945 -0.305054)
			(stroke
				(width 0.1)
				(type default)
			)
			(layer "B.Fab")
		)
		(fp_line
			(start 0.12065 0.3048)
			(end 0.67945 0.3048)
			(stroke
				(width 0.1)
				(type default)
			)
			(layer "B.Fab")
		)
		(fp_line
			(start -0.120396 0.3048)
			(end -0.120396 0.2794)
			(stroke
				(width 0.1)
				(type default)
			)
			(layer "B.Fab")
		)
		(fp_line
			(start -0.67945 0.3048)
			(end -0.120396 0.3048)
			(stroke
				(width 0.1)
				(type default)
			)
			(layer "B.Fab")
		)
		(pad "1" smd circle
			(at 0.40005 0 270)
			(size 0 0)
			(layers "B.Cu" "B.Mask" "B.Paste")
			(net "SPI_PEX2_CS_N")
		)
		(pad "2" smd circle
			(at -0.40005 0 270)
			(size 0 0)
			(layers "B.Cu" "B.Mask" "B.Paste")
			(net "P1V8_PEX")
		)
	)
	(footprint ""
		(layer "B.Cu")
		(at 128.095248 -174.746412)
		(property "Reference" "R1083"
			(at 0 0 0)
			(layer "B.SilkS")
			(hide yes)
			(effects
				(font
					(size 1.27 1.27)
				)
				(justify mirror)
			)
		)
		(property "Value" ""
			(at 0 0 0)
			(layer "B.Fab")
			(effects
				(font
					(size 1.27 1.27)
				)
				(justify mirror)
			)
		)
		(duplicate_pad_numbers_are_jumpers no)
		(fp_line
			(start -1.2954 -0.5842)
			(end -1.2954 0.5842)
			(stroke
				(width 0.1524)
				(type default)
			)
			(layer "B.SilkS")
		)
		(fp_line
			(start -1.2954 0.5842)
			(end 1.2954 0.5842)
			(stroke
				(width 0.1524)
				(type default)
			)
			(layer "B.SilkS")
		)
		(fp_line
			(start 1.2954 -0.5842)
			(end -1.2954 -0.5842)
			(stroke
				(width 0.1524)
				(type default)
			)
			(layer "B.SilkS")
		)
		(fp_line
			(start 1.2954 0.5842)
			(end 1.2954 -0.5842)
			(stroke
				(width 0.1524)
				(type default)
			)
			(layer "B.SilkS")
		)
		(fp_line
			(start -1.1938 -0.406654)
			(end -1.1938 0.4064)
			(stroke
				(width 0.1)
				(type default)
			)
			(layer "B.Fab")
		)
		(fp_line
			(start -1.1938 0.4064)
			(end -0.8636 0.4064)
			(stroke
				(width 0.1)
				(type default)
			)
			(layer "B.Fab")
		)
		(fp_line
			(start -0.8636 -0.4572)
			(end -0.8636 -0.406654)
			(stroke
				(width 0.1)
				(type default)
			)
			(layer "B.Fab")
		)
		(fp_line
			(start -0.8636 -0.406654)
			(end -1.1938 -0.406654)
			(stroke
				(width 0.1)
				(type default)
			)
			(layer "B.Fab")
		)
		(fp_line
			(start -0.8636 0.4064)
			(end -0.8636 0.4572)
			(stroke
				(width 0.1)
				(type default)
			)
			(layer "B.Fab")
		)
		(fp_line
			(start -0.8636 0.4572)
			(end 0.8636 0.4572)
			(stroke
				(width 0.1)
				(type default)
			)
			(layer "B.Fab")
		)
		(fp_line
			(start 0.8636 -0.4572)
			(end -0.8636 -0.4572)
			(stroke
				(width 0.1)
				(type default)
			)
			(layer "B.Fab")
		)
		(fp_line
			(start 0.8636 -0.406654)
			(end 0.8636 -0.4572)
			(stroke
				(width 0.1)
				(type default)
			)
			(layer "B.Fab")
		)
		(fp_line
			(start 0.8636 0.4064)
			(end 1.1938 0.4064)
			(stroke
				(width 0.1)
				(type default)
			)
			(layer "B.Fab")
		)
		(fp_line
			(start 0.8636 0.4318)
			(end 0.8636 0.4064)
			(stroke
				(width 0.1)
				(type default)
			)
			(layer "B.Fab")
		)
		(fp_line
			(start 0.8636 0.4572)
			(end 0.8636 0.4318)
			(stroke
				(width 0.1)
				(type default)
			)
			(layer "B.Fab")
		)
		(fp_line
			(start 1.1938 -0.406654)
			(end 0.8636 -0.406654)
			(stroke
				(width 0.1)
				(type default)
			)
			(layer "B.Fab")
		)
		(fp_line
			(start 1.1938 0.4064)
			(end 1.1938 -0.406654)
			(stroke
				(width 0.1)
				(type default)
			)
			(layer "B.Fab")
		)
		(pad "1" smd rect
			(at 0.7366 0 270)
			(size 0.7112 0.8128)
			(layers "B.Cu" "B.Mask" "B.Paste")
			(net "P3V3_DB2000QL_VDDR")
		)
		(pad "2" smd rect
			(at -0.7366 0 270)
			(size 0.7112 0.8128)
			(layers "B.Cu" "B.Mask" "B.Paste")
			(net "P3V3_DB2000QL_FB_VDD")
		)
	)
	(footprint ""
		(layer "B.Cu")
		(at 59.561476 -161.463736 180)
		(property "Reference" "Q1"
			(at 0.072136 1.843786 0)
			(unlocked yes)
			(layer "B.SilkS")
			(effects
				(font
					(size 0.7874 0.5842)
					(thickness 0.1524)
				)
				(justify mirror)
			)
		)
		(property "Value" ""
			(at 0 0 0)
			(layer "B.Fab")
			(effects
				(font
					(size 1.27 1.27)
				)
				(justify mirror)
			)
		)
		(duplicate_pad_numbers_are_jumpers no)
		(fp_line
			(start 1.38176 1.100074)
			(end -1.38176 1.100074)
			(stroke
				(width 0.1524)
				(type default)
			)
			(layer "B.SilkS")
		)
		(fp_line
			(start 1.38176 -1.100074)
			(end 1.38176 1.100074)
			(stroke
				(width 0.1524)
				(type default)
			)
			(layer "B.SilkS")
		)
		(fp_line
			(start 0.592074 -1.100074)
			(end 1.38176 -1.100074)
			(stroke
				(width 0.1524)
				(type default)
			)
			(layer "B.SilkS")
		)
		(fp_line
			(start 0 -0.508)
			(end 0.592074 -1.100074)
			(stroke
				(width 0.1524)
				(type default)
			)
			(layer "B.SilkS")
		)
		(fp_line
			(start -0.592074 -1.100074)
			(end 0 -0.508)
			(stroke
				(width 0.1524)
				(type default)
			)
			(layer "B.SilkS")
		)
		(fp_line
			(start -1.38176 1.100074)
			(end -1.38176 -1.100074)
			(stroke
				(width 0.1524)
				(type default)
			)
			(layer "B.SilkS")
		)
		(fp_line
			(start -1.38176 -1.100074)
			(end -0.592074 -1.100074)
			(stroke
				(width 0.1524)
				(type default)
			)
			(layer "B.SilkS")
		)
		(fp_poly
			(pts
				(xy 1.9431 -0.870204) (xy 1.50241 -0.649986) (xy 1.9431 -0.429768)
			)
			(stroke
				(width 0)
				(type default)
			)
			(fill yes)
			(layer "B.SilkS")
		)
		(fp_line
			(start 0.674878 1.100074)
			(end -0.674878 1.100074)
			(stroke
				(width 0.1)
				(type default)
			)
			(layer "B.Fab")
		)
		(fp_line
			(start 0.674878 -1.100074)
			(end 0.674878 1.100074)
			(stroke
				(width 0.1)
				(type default)
			)
			(layer "B.Fab")
		)
		(fp_line
			(start -0.674878 1.100074)
			(end -0.674878 -1.100074)
			(stroke
				(width 0.1)
				(type default)
			)
			(layer "B.Fab")
		)
		(fp_line
			(start -0.674878 -1.100074)
			(end 0.674878 -1.100074)
			(stroke
				(width 0.1)
				(type default)
			)
			(layer "B.Fab")
		)
		(fp_poly
			(pts
				(xy 1.9431 -0.870204) (xy 1.50241 -0.649986) (xy 1.9431 -0.429768)
			)
			(stroke
				(width 0)
				(type default)
			)
			(fill yes)
			(layer "B.Fab")
		)
		(pad "1" smd rect
			(at 0.94996 -0.649986 90)
			(size 0.4318 0.6096)
			(layers "B.Cu" "B.Mask" "B.Paste")
			(net "GND")
		)
		(pad "2" smd rect
			(at 0.94996 0 90)
			(size 0.4318 0.6096)
			(layers "B.Cu" "B.Mask" "B.Paste")
			(net "HP_NIC0_HSC_PWRGD_N")
		)
		(pad "3" smd rect
			(at 0.94996 0.649986 90)
			(size 0.4318 0.6096)
			(layers "B.Cu" "B.Mask" "B.Paste")
			(net "HP_NIC0_HSC_PWRGD_N")
		)
		(pad "4" smd rect
			(at -0.94996 0.649986 90)
			(size 0.4318 0.6096)
			(layers "B.Cu" "B.Mask" "B.Paste")
			(net "GND")
		)
		(pad "5" smd rect
			(at -0.94996 0 90)
			(size 0.4318 0.6096)
			(layers "B.Cu" "B.Mask" "B.Paste")
			(net "PWRGD_P12V_NIC0_R")
		)
		(pad "6" smd rect
			(at -0.94996 -0.649986 90)
			(size 0.4318 0.6096)
			(layers "B.Cu" "B.Mask" "B.Paste")
			(net "HP_NIC0_PWRGD_R")
		)
	)
	(footprint ""
		(layer "B.Cu")
		(at 256.87401 -222.299276 180)
		(property "Reference" "C2759"
			(at 0 0 0)
			(layer "B.SilkS")
			(hide yes)
			(effects
				(font
					(size 1.27 1.27)
				)
				(justify mirror)
			)
		)
		(property "Value" ""
			(at 0 0 0)
			(layer "B.Fab")
			(effects
				(font
					(size 1.27 1.27)
				)
				(justify mirror)
			)
		)
		(duplicate_pad_numbers_are_jumpers no)
		(fp_line
			(start 0.7874 0.4064)
			(end 0.7874 -0.4064)
			(stroke
				(width 0.1524)
				(type default)
			)
			(layer "B.SilkS")
		)
		(fp_line
			(start 0.7874 -0.4064)
			(end -0.7874 -0.4064)
			(stroke
				(width 0.1524)
				(type default)
			)
			(layer "B.SilkS")
		)
		(fp_line
			(start -0.7874 0.4064)
			(end 0.7874 0.4064)
			(stroke
				(width 0.1524)
				(type default)
			)
			(layer "B.SilkS")
		)
		(fp_line
			(start -0.7874 -0.4064)
			(end -0.7874 0.4064)
			(stroke
				(width 0.1524)
				(type default)
			)
			(layer "B.SilkS")
		)
		(fp_line
			(start 0.67945 0.3048)
			(end 0.67945 -0.305054)
			(stroke
				(width 0.1)
				(type default)
			)
			(layer "B.Fab")
		)
		(fp_line
			(start 0.67945 -0.305054)
			(end 0.12065 -0.305054)
			(stroke
				(width 0.1)
				(type default)
			)
			(layer "B.Fab")
		)
		(fp_line
			(start 0.12065 0.3048)
			(end 0.67945 0.3048)
			(stroke
				(width 0.1)
				(type default)
			)
			(layer "B.Fab")
		)
		(fp_line
			(start 0.12065 0.2794)
			(end 0.12065 0.3048)
			(stroke
				(width 0.1)
				(type default)
			)
			(layer "B.Fab")
		)
		(fp_line
			(start 0.12065 -0.2794)
			(end -0.12065 -0.2794)
			(stroke
				(width 0.1)
				(type default)
			)
			(layer "B.Fab")
		)
		(fp_line
			(start 0.12065 -0.305054)
			(end 0.12065 -0.2794)
			(stroke
				(width 0.1)
				(type default)
			)
			(layer "B.Fab")
		)
		(fp_line
			(start -0.120396 0.3048)
			(end -0.120396 0.2794)
			(stroke
				(width 0.1)
				(type default)
			)
			(layer "B.Fab")
		)
		(fp_line
			(start -0.120396 0.2794)
			(end 0.12065 0.2794)
			(stroke
				(width 0.1)
				(type default)
			)
			(layer "B.Fab")
		)
		(fp_line
			(start -0.12065 -0.2794)
			(end -0.12065 -0.3048)
			(stroke
				(width 0.1)
				(type default)
			)
			(layer "B.Fab")
		)
		(fp_line
			(start -0.12065 -0.3048)
			(end -0.67945 -0.3048)
			(stroke
				(width 0.1)
				(type default)
			)
			(layer "B.Fab")
		)
		(fp_line
			(start -0.67945 0.3048)
			(end -0.120396 0.3048)
			(stroke
				(width 0.1)
				(type default)
			)
			(layer "B.Fab")
		)
		(fp_line
			(start -0.67945 -0.3048)
			(end -0.67945 0.3048)
			(stroke
				(width 0.1)
				(type default)
			)
			(layer "B.Fab")
		)
		(pad "1" smd circle
			(at 0.40005 0)
			(size 0 0)
			(layers "B.Cu" "B.Mask" "B.Paste")
			(net "GND")
		)
		(pad "2" smd circle
			(at -0.40005 0)
			(size 0 0)
			(layers "B.Cu" "B.Mask" "B.Paste")
			(net "P1V8_PEX")
		)
	)
)
